(kicad_pcb
	(version 20260206)
	(generator "pcbnew")
	(generator_version "10.0")
	(general
		(thickness 1.6)
		(legacy_teardrops no)
	)
	(paper "A4")
	(title_block
		(title "03242023_DA0F0TMBIJ0_F0T_Motherboard_J_brd_V01_OCP.brd")
		(comment 1 "Grand Teton / footprints 3294-3299 of 6105")
	)
	(layers
		(0 "F.Cu" signal "TOP")
		(4 "In1.Cu" signal "GND")
		(6 "In2.Cu" signal "IN1")
		(8 "In3.Cu" signal "GND1")
		(10 "In4.Cu" signal "IN2")
		(12 "In5.Cu" signal "GND2")
		(14 "In6.Cu" signal "IN3")
		(16 "In7.Cu" signal "GND3")
		(18 "In8.Cu" signal "VCC")
		(20 "In9.Cu" signal "VCC1")
		(22 "In10.Cu" signal "GND4")
		(24 "In11.Cu" signal "IN4")
		(26 "In12.Cu" signal "GND5")
		(28 "In13.Cu" signal "IN5")
		(30 "In14.Cu" signal "GND6")
		(32 "In15.Cu" signal "IN6")
		(34 "In16.Cu" signal "GND7")
		(2 "B.Cu" signal "BOTTOM")
		(9 "F.Adhes" user "F.Adhesive")
		(11 "B.Adhes" user "B.Adhesive")
		(13 "F.Paste" user "Package Geometry/Pastemask Top")
		(15 "B.Paste" user "Package Geometry/Pastemask Bottom")
		(5 "F.SilkS" user "Ref Des/Silkscreen Top")
		(7 "B.SilkS" user "Ref Des/Silkscreen Bottom")
		(1 "F.Mask" user "Board Geometry/Soldermask Top")
		(3 "B.Mask" user "Board Geometry/Soldermask Bottom")
		(17 "Dwgs.User" user "User.Drawings")
		(19 "Cmts.User" user "User.Comments")
		(21 "Eco1.User" user "User.Eco1")
		(23 "Eco2.User" user "User.Eco2")
		(25 "Edge.Cuts" user "Board Geometry/Outline")
		(27 "Margin" user)
		(31 "F.CrtYd" user "Package Geometry/Place Bound Top")
		(29 "B.CrtYd" user "Package Geometry/Place Bound Bottom")
		(35 "F.Fab" user "Ref Des/Assembly Top")
		(33 "B.Fab" user "Ref Des/Assembly Bottom")
	)
	(footprint ""
		(layer "F.Cu")
		(at 197.41388 -106.225848)
		(property "Reference" "R990"
			(at 0 0 0)
			(layer "F.SilkS")
			(hide yes)
			(effects
				(font
					(size 1.27 1.27)
				)
			)
		)
		(property "Value" ""
			(at 0 0 0)
			(layer "F.Fab")
			(effects
				(font
					(size 1.27 1.27)
				)
			)
		)
		(duplicate_pad_numbers_are_jumpers no)
		(fp_line
			(start -0.7874 -0.4064)
			(end 0.7874 -0.4064)
			(stroke
				(width 0.1524)
				(type default)
			)
			(layer "F.SilkS")
		)
		(fp_line
			(start -0.7874 0.4064)
			(end -0.7874 -0.4064)
			(stroke
				(width 0.1524)
				(type default)
			)
			(layer "F.SilkS")
		)
		(fp_line
			(start 0.7874 -0.4064)
			(end 0.7874 0.4064)
			(stroke
				(width 0.1524)
				(type default)
			)
			(layer "F.SilkS")
		)
		(fp_line
			(start 0.7874 0.4064)
			(end -0.7874 0.4064)
			(stroke
				(width 0.1524)
				(type default)
			)
			(layer "F.SilkS")
		)
		(fp_line
			(start -0.67945 -0.305054)
			(end -0.12065 -0.305054)
			(stroke
				(width 0.1)
				(type default)
			)
			(layer "F.Fab")
		)
		(fp_line
			(start -0.67945 0.3048)
			(end -0.67945 -0.305054)
			(stroke
				(width 0.1)
				(type default)
			)
			(layer "F.Fab")
		)
		(fp_line
			(start -0.12065 -0.305054)
			(end -0.12065 -0.2794)
			(stroke
				(width 0.1)
				(type default)
			)
			(layer "F.Fab")
		)
		(fp_line
			(start -0.12065 -0.2794)
			(end 0.12065 -0.2794)
			(stroke
				(width 0.1)
				(type default)
			)
			(layer "F.Fab")
		)
		(fp_line
			(start -0.12065 0.2794)
			(end -0.12065 0.3048)
			(stroke
				(width 0.1)
				(type default)
			)
			(layer "F.Fab")
		)
		(fp_line
			(start -0.12065 0.3048)
			(end -0.67945 0.3048)
			(stroke
				(width 0.1)
				(type default)
			)
			(layer "F.Fab")
		)
		(fp_line
			(start 0.120396 0.2794)
			(end -0.12065 0.2794)
			(stroke
				(width 0.1)
				(type default)
			)
			(layer "F.Fab")
		)
		(fp_line
			(start 0.120396 0.3048)
			(end 0.120396 0.2794)
			(stroke
				(width 0.1)
				(type default)
			)
			(layer "F.Fab")
		)
		(fp_line
			(start 0.12065 -0.3048)
			(end 0.67945 -0.3048)
			(stroke
				(width 0.1)
				(type default)
			)
			(layer "F.Fab")
		)
		(fp_line
			(start 0.12065 -0.2794)
			(end 0.12065 -0.3048)
			(stroke
				(width 0.1)
				(type default)
			)
			(layer "F.Fab")
		)
		(fp_line
			(start 0.67945 -0.3048)
			(end 0.67945 0.3048)
			(stroke
				(width 0.1)
				(type default)
			)
			(layer "F.Fab")
		)
		(fp_line
			(start 0.67945 0.3048)
			(end 0.120396 0.3048)
			(stroke
				(width 0.1)
				(type default)
			)
			(layer "F.Fab")
		)
		(pad "1" smd circle
			(at -0.40005 0)
			(size 0 0)
			(layers "F.Cu" "F.Mask" "F.Paste")
			(net "FM_PLD_CLK_25M_R_EN")
		)
		(pad "2" smd circle
			(at 0.40005 0)
			(size 0 0)
			(layers "F.Cu" "F.Mask" "F.Paste")
			(net "GND")
		)
	)
	(footprint ""
		(layer "F.Cu")
		(at 376.296936 -92.910152 -90)
		(property "Reference" "R483"
			(at 0 0 270)
			(layer "F.SilkS")
			(hide yes)
			(effects
				(font
					(size 1.27 1.27)
				)
			)
		)
		(property "Value" ""
			(at 0 0 270)
			(layer "F.Fab")
			(effects
				(font
					(size 1.27 1.27)
				)
			)
		)
		(duplicate_pad_numbers_are_jumpers no)
		(fp_line
			(start -0.7874 0.4064)
			(end -0.7874 -0.4064)
			(stroke
				(width 0.1524)
				(type default)
			)
			(layer "F.SilkS")
		)
		(fp_line
			(start 0.7874 0.4064)
			(end -0.7874 0.4064)
			(stroke
				(width 0.1524)
				(type default)
			)
			(layer "F.SilkS")
		)
		(fp_line
			(start -0.7874 -0.4064)
			(end 0.7874 -0.4064)
			(stroke
				(width 0.1524)
				(type default)
			)
			(layer "F.SilkS")
		)
		(fp_line
			(start 0.7874 -0.4064)
			(end 0.7874 0.4064)
			(stroke
				(width 0.1524)
				(type default)
			)
			(layer "F.SilkS")
		)
		(fp_line
			(start -0.67945 0.3048)
			(end -0.67945 -0.305054)
			(stroke
				(width 0.1)
				(type default)
			)
			(layer "F.Fab")
		)
		(fp_line
			(start -0.12065 0.3048)
			(end -0.67945 0.3048)
			(stroke
				(width 0.1)
				(type default)
			)
			(layer "F.Fab")
		)
		(fp_line
			(start 0.120396 0.3048)
			(end 0.120396 0.2794)
			(stroke
				(width 0.1)
				(type default)
			)
			(layer "F.Fab")
		)
		(fp_line
			(start 0.67945 0.3048)
			(end 0.120396 0.3048)
			(stroke
				(width 0.1)
				(type default)
			)
			(layer "F.Fab")
		)
		(fp_line
			(start -0.12065 0.2794)
			(end -0.12065 0.3048)
			(stroke
				(width 0.1)
				(type default)
			)
			(layer "F.Fab")
		)
		(fp_line
			(start 0.120396 0.2794)
			(end -0.12065 0.2794)
			(stroke
				(width 0.1)
				(type default)
			)
			(layer "F.Fab")
		)
		(fp_line
			(start -0.12065 -0.2794)
			(end 0.12065 -0.2794)
			(stroke
				(width 0.1)
				(type default)
			)
			(layer "F.Fab")
		)
		(fp_line
			(start 0.12065 -0.2794)
			(end 0.12065 -0.3048)
			(stroke
				(width 0.1)
				(type default)
			)
			(layer "F.Fab")
		)
		(fp_line
			(start 0.12065 -0.3048)
			(end 0.67945 -0.3048)
			(stroke
				(width 0.1)
				(type default)
			)
			(layer "F.Fab")
		)
		(fp_line
			(start 0.67945 -0.3048)
			(end 0.67945 0.3048)
			(stroke
				(width 0.1)
				(type default)
			)
			(layer "F.Fab")
		)
		(fp_line
			(start -0.67945 -0.305054)
			(end -0.12065 -0.305054)
			(stroke
				(width 0.1)
				(type default)
			)
			(layer "F.Fab")
		)
		(fp_line
			(start -0.12065 -0.305054)
			(end -0.12065 -0.2794)
			(stroke
				(width 0.1)
				(type default)
			)
			(layer "F.Fab")
		)
		(pad "1" smd circle
			(at -0.40005 0 270)
			(size 0 0)
			(layers "F.Cu" "F.Mask" "F.Paste")
			(net "JTAG_BMC_DBP_TDO_R")
		)
		(pad "2" smd circle
			(at 0.40005 0 270)
			(size 0 0)
			(layers "F.Cu" "F.Mask" "F.Paste")
			(net "JTAG_BMC_DBP_TDO")
		)
	)
	(footprint ""
		(layer "F.Cu")
		(at 121.708926 -119.810784 -90)
		(property "Reference" "R860"
			(at 0 0 270)
			(layer "F.SilkS")
			(hide yes)
			(effects
				(font
					(size 1.27 1.27)
				)
			)
		)
		(property "Value" ""
			(at 0 0 270)
			(layer "F.Fab")
			(effects
				(font
					(size 1.27 1.27)
				)
			)
		)
		(duplicate_pad_numbers_are_jumpers no)
		(fp_line
			(start -0.7874 0.4064)
			(end -0.7874 -0.4064)
			(stroke
				(width 0.1524)
				(type default)
			)
			(layer "F.SilkS")
		)
		(fp_line
			(start 0.7874 0.4064)
			(end -0.7874 0.4064)
			(stroke
				(width 0.1524)
				(type default)
			)
			(layer "F.SilkS")
		)
		(fp_line
			(start -0.7874 -0.4064)
			(end 0.7874 -0.4064)
			(stroke
				(width 0.1524)
				(type default)
			)
			(layer "F.SilkS")
		)
		(fp_line
			(start 0.7874 -0.4064)
			(end 0.7874 0.4064)
			(stroke
				(width 0.1524)
				(type default)
			)
			(layer "F.SilkS")
		)
		(fp_line
			(start -0.67945 0.3048)
			(end -0.67945 -0.305054)
			(stroke
				(width 0.1)
				(type default)
			)
			(layer "F.Fab")
		)
		(fp_line
			(start -0.12065 0.3048)
			(end -0.67945 0.3048)
			(stroke
				(width 0.1)
				(type default)
			)
			(layer "F.Fab")
		)
		(fp_line
			(start 0.120396 0.3048)
			(end 0.120396 0.2794)
			(stroke
				(width 0.1)
				(type default)
			)
			(layer "F.Fab")
		)
		(fp_line
			(start 0.67945 0.3048)
			(end 0.120396 0.3048)
			(stroke
				(width 0.1)
				(type default)
			)
			(layer "F.Fab")
		)
		(fp_line
			(start -0.12065 0.2794)
			(end -0.12065 0.3048)
			(stroke
				(width 0.1)
				(type default)
			)
			(layer "F.Fab")
		)
		(fp_line
			(start 0.120396 0.2794)
			(end -0.12065 0.2794)
			(stroke
				(width 0.1)
				(type default)
			)
			(layer "F.Fab")
		)
		(fp_line
			(start -0.12065 -0.2794)
			(end 0.12065 -0.2794)
			(stroke
				(width 0.1)
				(type default)
			)
			(layer "F.Fab")
		)
		(fp_line
			(start 0.12065 -0.2794)
			(end 0.12065 -0.3048)
			(stroke
				(width 0.1)
				(type default)
			)
			(layer "F.Fab")
		)
		(fp_line
			(start 0.12065 -0.3048)
			(end 0.67945 -0.3048)
			(stroke
				(width 0.1)
				(type default)
			)
			(layer "F.Fab")
		)
		(fp_line
			(start 0.67945 -0.3048)
			(end 0.67945 0.3048)
			(stroke
				(width 0.1)
				(type default)
			)
			(layer "F.Fab")
		)
		(fp_line
			(start -0.67945 -0.305054)
			(end -0.12065 -0.305054)
			(stroke
				(width 0.1)
				(type default)
			)
			(layer "F.Fab")
		)
		(fp_line
			(start -0.12065 -0.305054)
			(end -0.12065 -0.2794)
			(stroke
				(width 0.1)
				(type default)
			)
			(layer "F.Fab")
		)
		(pad "1" smd circle
			(at -0.40005 0 270)
			(size 0 0)
			(layers "F.Cu" "F.Mask" "F.Paste")
			(net "RST_CPU1_DRAM_CD_N")
		)
		(pad "2" smd circle
			(at 0.40005 0 270)
			(size 0 0)
			(layers "F.Cu" "F.Mask" "F.Paste")
			(net "RST_CPU1_DRAM_CD_PLD_N")
		)
	)
	(footprint ""
		(layer "F.Cu")
		(at 293.80688 -46.954948 90)
		(property "Reference" "R4064"
			(at 0 0 90)
			(layer "F.SilkS")
			(hide yes)
			(effects
				(font
					(size 1.27 1.27)
				)
			)
		)
		(property "Value" ""
			(at 0 0 90)
			(layer "F.Fab")
			(effects
				(font
					(size 1.27 1.27)
				)
			)
		)
		(duplicate_pad_numbers_are_jumpers no)
		(fp_line
			(start 0.7874 -0.4064)
			(end 0.7874 0.4064)
			(stroke
				(width 0.1524)
				(type default)
			)
			(layer "F.SilkS")
		)
		(fp_line
			(start -0.7874 -0.4064)
			(end 0.7874 -0.4064)
			(stroke
				(width 0.1524)
				(type default)
			)
			(layer "F.SilkS")
		)
		(fp_line
			(start 0.7874 0.4064)
			(end -0.7874 0.4064)
			(stroke
				(width 0.1524)
				(type default)
			)
			(layer "F.SilkS")
		)
		(fp_line
			(start -0.7874 0.4064)
			(end -0.7874 -0.4064)
			(stroke
				(width 0.1524)
				(type default)
			)
			(layer "F.SilkS")
		)
		(fp_line
			(start -0.12065 -0.305054)
			(end -0.12065 -0.2794)
			(stroke
				(width 0.1)
				(type default)
			)
			(layer "F.Fab")
		)
		(fp_line
			(start -0.67945 -0.305054)
			(end -0.12065 -0.305054)
			(stroke
				(width 0.1)
				(type default)
			)
			(layer "F.Fab")
		)
		(fp_line
			(start 0.67945 -0.3048)
			(end 0.67945 0.3048)
			(stroke
				(width 0.1)
				(type default)
			)
			(layer "F.Fab")
		)
		(fp_line
			(start 0.12065 -0.3048)
			(end 0.67945 -0.3048)
			(stroke
				(width 0.1)
				(type default)
			)
			(layer "F.Fab")
		)
		(fp_line
			(start 0.12065 -0.2794)
			(end 0.12065 -0.3048)
			(stroke
				(width 0.1)
				(type default)
			)
			(layer "F.Fab")
		)
		(fp_line
			(start -0.12065 -0.2794)
			(end 0.12065 -0.2794)
			(stroke
				(width 0.1)
				(type default)
			)
			(layer "F.Fab")
		)
		(fp_line
			(start 0.120396 0.2794)
			(end -0.12065 0.2794)
			(stroke
				(width 0.1)
				(type default)
			)
			(layer "F.Fab")
		)
		(fp_line
			(start -0.12065 0.2794)
			(end -0.12065 0.3048)
			(stroke
				(width 0.1)
				(type default)
			)
			(layer "F.Fab")
		)
		(fp_line
			(start 0.67945 0.3048)
			(end 0.120396 0.3048)
			(stroke
				(width 0.1)
				(type default)
			)
			(layer "F.Fab")
		)
		(fp_line
			(start 0.120396 0.3048)
			(end 0.120396 0.2794)
			(stroke
				(width 0.1)
				(type default)
			)
			(layer "F.Fab")
		)
		(fp_line
			(start -0.12065 0.3048)
			(end -0.67945 0.3048)
			(stroke
				(width 0.1)
				(type default)
			)
			(layer "F.Fab")
		)
		(fp_line
			(start -0.67945 0.3048)
			(end -0.67945 -0.305054)
			(stroke
				(width 0.1)
				(type default)
			)
			(layer "F.Fab")
		)
		(pad "1" smd circle
			(at -0.40005 0 90)
			(size 0 0)
			(layers "F.Cu" "F.Mask" "F.Paste")
			(net "E1S_0_EN")
		)
		(pad "2" smd circle
			(at 0.40005 0 90)
			(size 0 0)
			(layers "F.Cu" "F.Mask" "F.Paste")
			(net "P12V_E1S_EN_0_R")
		)
	)
	(footprint ""
		(layer "F.Cu")
		(at 305.92014 -435.6481 90)
		(property "Reference" "Q133"
			(at -7.36346 -4.155948 90)
			(unlocked yes)
			(layer "F.SilkS")
			(effects
				(font
					(size 0.7874 0.5842)
					(thickness 0.1524)
				)
				(justify left)
			)
		)
		(property "Value" ""
			(at 0 0 90)
			(layer "F.Fab")
			(effects
				(font
					(size 1.27 1.27)
				)
			)
		)
		(duplicate_pad_numbers_are_jumpers no)
		(fp_line
			(start 1.332738 -1.100074)
			(end 1.332738 1.100074)
			(stroke
				(width 0.1524)
				(type default)
			)
			(layer "F.SilkS")
		)
		(fp_line
			(start 0.4826 -1.100074)
			(end 1.332738 -1.100074)
			(stroke
				(width 0.1524)
				(type default)
			)
			(layer "F.SilkS")
		)
		(fp_line
			(start -0.4826 -1.100074)
			(end 0 -0.541274)
			(stroke
				(width 0.1524)
				(type default)
			)
			(layer "F.SilkS")
		)
		(fp_line
			(start -1.332738 -1.100074)
			(end -0.4826 -1.100074)
			(stroke
				(width 0.1524)
				(type default)
			)
			(layer "F.SilkS")
		)
		(fp_line
			(start 0 -0.541274)
			(end 0.4826 -1.100074)
			(stroke
				(width 0.1524)
				(type default)
			)
			(layer "F.SilkS")
		)
		(fp_line
			(start 1.332738 1.100074)
			(end -1.332738 1.100074)
			(stroke
				(width 0.1524)
				(type default)
			)
			(layer "F.SilkS")
		)
		(fp_line
			(start -1.332738 1.100074)
			(end -1.332738 -1.100074)
			(stroke
				(width 0.1524)
				(type default)
			)
			(layer "F.SilkS")
		)
		(fp_poly
			(pts
				(xy -2.29362 -1.321054) (xy -1.591564 -0.970026) (xy -2.29362 -0.618998)
			)
			(stroke
				(width 0)
				(type default)
			)
			(fill yes)
			(layer "F.SilkS")
		)
		(fp_line
			(start 0.674878 -1.100074)
			(end 0.674878 1.100074)
			(stroke
				(width 0.1)
				(type default)
			)
			(layer "F.Fab")
		)
		(fp_line
			(start -0.674878 -1.100074)
			(end 0.674878 -1.100074)
			(stroke
				(width 0.1)
				(type default)
			)
			(layer "F.Fab")
		)
		(fp_line
			(start 0.674878 1.100074)
			(end -0.674878 1.100074)
			(stroke
				(width 0.1)
				(type default)
			)
			(layer "F.Fab")
		)
		(fp_line
			(start -0.674878 1.100074)
			(end -0.674878 -1.100074)
			(stroke
				(width 0.1)
				(type default)
			)
			(layer "F.Fab")
		)
		(fp_poly
			(pts
				(xy -2.2352 -0.298958) (xy -2.2352 -1.001014) (xy -1.533144 -0.649986)
			)
			(stroke
				(width 0)
				(type default)
			)
			(fill yes)
			(layer "F.Fab")
		)
		(pad "1" smd rect
			(at -0.94996 -0.649986 180)
			(size 0.4318 0.508)
			(layers "F.Cu" "F.Mask" "F.Paste")
			(net "GND")
		)
		(pad "2" smd rect
			(at -0.94996 0 180)
			(size 0.4318 0.508)
			(layers "F.Cu" "F.Mask" "F.Paste")
			(net "PRSNT_CABLE_GPU_A2_N")
		)
		(pad "3" smd rect
			(at -0.94996 0.649986 180)
			(size 0.4318 0.508)
			(layers "F.Cu" "F.Mask" "F.Paste")
			(net "PRSNT_CABLE_GPU_A2_ISO_N")
		)
		(pad "4" smd rect
			(at 0.94996 0.649986 180)
			(size 0.4318 0.508)
			(layers "F.Cu" "F.Mask" "F.Paste")
			(net "GND")
		)
		(pad "5" smd rect
			(at 0.94996 0 180)
			(size 0.4318 0.508)
			(layers "F.Cu" "F.Mask" "F.Paste")
			(net "PRSNT_CABLE_GPU_A2")
		)
		(pad "6" smd rect
			(at 0.94996 -0.649986 180)
			(size 0.4318 0.508)
			(layers "F.Cu" "F.Mask" "F.Paste")
			(net "PRSNT_CABLE_GPU_A2")
		)
	)
	(footprint ""
		(layer "F.Cu")
		(at 292.928802 -57.509918 -90)
		(property "Reference" "Q126"
			(at 0.4572 7.436612 0)
			(unlocked yes)
			(layer "F.SilkS")
			(effects
				(font
					(size 0.7874 0.5842)
					(thickness 0.1524)
				)
				(justify left)
			)
		)
		(property "Value" ""
			(at 0 0 270)
			(layer "F.Fab")
			(effects
				(font
					(size 1.27 1.27)
				)
			)
		)
		(duplicate_pad_numbers_are_jumpers no)
		(fp_line
			(start -1.332738 1.100074)
			(end -1.332738 -1.100074)
			(stroke
				(width 0.1524)
				(type default)
			)
			(layer "F.SilkS")
		)
		(fp_line
			(start 1.332738 1.100074)
			(end -1.332738 1.100074)
			(stroke
				(width 0.1524)
				(type default)
			)
			(layer "F.SilkS")
		)
		(fp_line
			(start 0 -0.541274)
			(end 0.4826 -1.100074)
			(stroke
				(width 0.1524)
				(type default)
			)
			(layer "F.SilkS")
		)
		(fp_line
			(start -1.332738 -1.100074)
			(end -0.4826 -1.100074)
			(stroke
				(width 0.1524)
				(type default)
			)
			(layer "F.SilkS")
		)
		(fp_line
			(start -0.4826 -1.100074)
			(end 0 -0.541274)
			(stroke
				(width 0.1524)
				(type default)
			)
			(layer "F.SilkS")
		)
		(fp_line
			(start 0.4826 -1.100074)
			(end 1.332738 -1.100074)
			(stroke
				(width 0.1524)
				(type default)
			)
			(layer "F.SilkS")
		)
		(fp_line
			(start 1.332738 -1.100074)
			(end 1.332738 1.100074)
			(stroke
				(width 0.1524)
				(type default)
			)
			(layer "F.SilkS")
		)
		(fp_poly
			(pts
				(xy -2.2352 -1.001014) (xy -1.533144 -0.649986) (xy -2.2352 -0.298958)
			)
			(stroke
				(width 0)
				(type default)
			)
			(fill yes)
			(layer "F.SilkS")
		)
		(fp_line
			(start -0.674878 1.100074)
			(end -0.674878 -1.100074)
			(stroke
				(width 0.1)
				(type default)
			)
			(layer "F.Fab")
		)
		(fp_line
			(start 0.674878 1.100074)
			(end -0.674878 1.100074)
			(stroke
				(width 0.1)
				(type default)
			)
			(layer "F.Fab")
		)
		(fp_line
			(start -0.674878 -1.100074)
			(end 0.674878 -1.100074)
			(stroke
				(width 0.1)
				(type default)
			)
			(layer "F.Fab")
		)
		(fp_line
			(start 0.674878 -1.100074)
			(end 0.674878 1.100074)
			(stroke
				(width 0.1)
				(type default)
			)
			(layer "F.Fab")
		)
		(fp_poly
			(pts
				(xy -2.2352 -0.298958) (xy -2.2352 -1.001014) (xy -1.533144 -0.649986)
			)
			(stroke
				(width 0)
				(type default)
			)
			(fill yes)
			(layer "F.Fab")
		)
		(pad "1" smd rect
			(at -0.94996 -0.649986)
			(size 0.4318 0.508)
			(layers "F.Cu" "F.Mask" "F.Paste")
			(net "GND")
		)
		(pad "2" smd rect
			(at -0.94996 0)
			(size 0.4318 0.508)
			(layers "F.Cu" "F.Mask" "F.Paste")
			(net "P3V3_E1S_EN_1_R")
		)
		(pad "3" smd rect
			(at -0.94996 0.649986)
			(size 0.4318 0.508)
			(layers "F.Cu" "F.Mask" "F.Paste")
			(net "P3V3_E1S_UV_0_R")
		)
		(pad "4" smd rect
			(at 0.94996 0.649986)
			(size 0.4318 0.508)
			(layers "F.Cu" "F.Mask" "F.Paste")
			(net "GND")
		)
		(pad "5" smd rect
			(at 0.94996 0)
			(size 0.4318 0.508)
			(layers "F.Cu" "F.Mask" "F.Paste")
			(net "P3V3_E1S_0_EN_G")
		)
		(pad "6" smd rect
			(at 0.94996 -0.649986)
			(size 0.4318 0.508)
			(layers "F.Cu" "F.Mask" "F.Paste")
			(net "P3V3_E1S_0_EN_G")
		)
	)
)
